(kicad_pcb
	(version 20260206)
	(generator "pcbnew")
	(generator_version "10.0")
	(general
		(thickness 1.6)
		(legacy_teardrops no)
	)
	(paper "A4")
	(title_block
		(title "peb — Lightning_PEB_BRD.brd")
		(comment 1 "Lightning (Wiwynn / Facebook NVMe JBOF) / footprints 2514-2520 of 2563")
	)
	(layers
		(0 "F.Cu" signal "TOP")
		(4 "In1.Cu" signal "L2GND")
		(6 "In2.Cu" signal "L3")
		(8 "In3.Cu" signal "L4VCC")
		(10 "In4.Cu" signal "L5VCC")
		(12 "In5.Cu" signal "L6")
		(14 "In6.Cu" signal "L7GND")
		(2 "B.Cu" signal "BOTTOM")
		(9 "F.Adhes" user "F.Adhesive")
		(11 "B.Adhes" user "B.Adhesive")
		(13 "F.Paste" user "Package Geometry/Pastemask Top")
		(15 "B.Paste" user "Package Geometry/Pastemask Bottom")
		(5 "F.SilkS" user "Ref Des/Silkscreen Top")
		(7 "B.SilkS" user "Ref Des/Silkscreen Bottom")
		(1 "F.Mask" user "Board Geometry/Soldermask Top")
		(3 "B.Mask" user "Board Geometry/Soldermask Bottom")
		(17 "Dwgs.User" user "User.Drawings")
		(19 "Cmts.User" user "User.Comments")
		(21 "Eco1.User" user "User.Eco1")
		(23 "Eco2.User" user "User.Eco2")
		(25 "Edge.Cuts" user "Board Geometry/Outline")
		(27 "Margin" user)
		(31 "F.CrtYd" user "Package Geometry/Place Bound Top")
		(29 "B.CrtYd" user "Package Geometry/Place Bound Bottom")
		(35 "F.Fab" user "Ref Des/Assembly Top")
		(33 "B.Fab" user "Ref Des/Assembly Bottom")
	)
	(footprint ""
		(layer "B.Cu")
		(at 229.5906 -28.575 90)
		(property "Reference" "R27"
			(at 0 0 90)
			(layer "B.SilkS")
			(hide yes)
			(effects
				(font
					(size 1.27 1.27)
				)
				(justify mirror)
			)
		)
		(property "Value" "0R2J-2-GP"
			(at -0.064008 -3.993896 90)
			(unlocked yes)
			(layer "B.Fab")
			(hide yes)
			(effects
				(font
					(size 1.016 1.016)
					(thickness 0.1524)
				)
				(justify mirror)
			)
		)
		(property "Device Type" "R402H16"
			(at -0.064008 -5.517896 90)
			(unlocked yes)
			(layer "B.Fab")
			(hide yes)
			(effects
				(font
					(size 1.016 1.016)
					(thickness 0.1524)
				)
				(justify mirror)
			)
		)
		(duplicate_pad_numbers_are_jumpers no)
		(fp_line
			(start 0.508 -0.9398)
			(end 0.508 0.9398)
			(stroke
				(width 0.1524)
				(type default)
			)
			(layer "B.SilkS")
		)
		(fp_line
			(start -0.508 -0.9398)
			(end 0.508 -0.9398)
			(stroke
				(width 0.1524)
				(type default)
			)
			(layer "B.SilkS")
		)
		(fp_rect
			(start 0.508 0.9398)
			(end -0.508 -0.9398)
			(stroke
				(width 0)
				(type default)
			)
			(fill no)
			(layer "B.CrtYd")
		)
		(fp_rect
			(start 0.508 0.9398)
			(end -0.508 -0.9398)
			(stroke
				(width 0)
				(type default)
			)
			(fill no)
			(layer "B.Fab")
		)
		(pad "1" smd custom
			(at 0 -0.4445 270)
			(size 0.1397 0.1397)
			(layers "B.Cu" "B.Mask" "B.Paste")
			(net "VSS_571")
			(options
				(clearance outline)
				(anchor circle)
			)
			(primitives
				(gr_poly
					(pts
						(arc
							(start -0.1778 0.2794)
							(mid -0.249642 0.249642)
							(end -0.2794 0.1778)
						)
						(arc
							(start -0.2794 -0.1778)
							(mid -0.249642 -0.249642)
							(end -0.1778 -0.2794)
						)
						(arc
							(start 0.1778 -0.2794)
							(mid 0.249642 -0.249642)
							(end 0.2794 -0.1778)
						)
						(arc
							(start 0.2794 0.1778)
							(mid 0.249642 0.249642)
							(end 0.1778 0.2794)
						)
					)
					(width 0)
					(fill yes)
				)
			)
		)
		(pad "2" smd custom
			(at 0 0.4445 270)
			(size 0.1397 0.1397)
			(layers "B.Cu" "B.Mask" "B.Paste")
			(net "GND")
			(options
				(clearance outline)
				(anchor circle)
			)
			(primitives
				(gr_poly
					(pts
						(arc
							(start -0.1778 0.2794)
							(mid -0.249642 0.249642)
							(end -0.2794 0.1778)
						)
						(arc
							(start -0.2794 -0.1778)
							(mid -0.249642 -0.249642)
							(end -0.1778 -0.2794)
						)
						(arc
							(start 0.1778 -0.2794)
							(mid 0.249642 -0.249642)
							(end 0.2794 -0.1778)
						)
						(arc
							(start 0.2794 0.1778)
							(mid 0.249642 0.249642)
							(end 0.1778 0.2794)
						)
					)
					(width 0)
					(fill yes)
				)
			)
		)
	)
	(footprint ""
		(layer "B.Cu")
		(at 251.600208 -26.1112 180)
		(property "Reference" "R776"
			(at 0 0 0)
			(layer "B.SilkS")
			(hide yes)
			(effects
				(font
					(size 1.27 1.27)
				)
				(justify mirror)
			)
		)
		(property "Value" "3K3R2F-2-GP"
			(at -0.064008 -3.993896 180)
			(unlocked yes)
			(layer "B.Fab")
			(hide yes)
			(effects
				(font
					(size 1.016 1.016)
					(thickness 0.1524)
				)
				(justify mirror)
			)
		)
		(property "Device Type" "R402H16"
			(at -0.064008 -5.517896 180)
			(unlocked yes)
			(layer "B.Fab")
			(hide yes)
			(effects
				(font
					(size 1.016 1.016)
					(thickness 0.1524)
				)
				(justify mirror)
			)
		)
		(duplicate_pad_numbers_are_jumpers no)
		(fp_line
			(start 0.508 -0.9398)
			(end 0.508 0.9398)
			(stroke
				(width 0.1524)
				(type default)
			)
			(layer "B.SilkS")
		)
		(fp_line
			(start -0.508 -0.9398)
			(end 0.508 -0.9398)
			(stroke
				(width 0.1524)
				(type default)
			)
			(layer "B.SilkS")
		)
		(fp_rect
			(start 0.508 0.9398)
			(end -0.508 -0.9398)
			(stroke
				(width 0)
				(type default)
			)
			(fill no)
			(layer "B.CrtYd")
		)
		(fp_rect
			(start 0.508 0.9398)
			(end -0.508 -0.9398)
			(stroke
				(width 0)
				(type default)
			)
			(fill no)
			(layer "B.Fab")
		)
		(pad "1" smd custom
			(at 0 -0.4445)
			(size 0.1397 0.1397)
			(layers "B.Cu" "B.Mask" "B.Paste")
			(net "P3V3_GPIO")
			(options
				(clearance outline)
				(anchor circle)
			)
			(primitives
				(gr_poly
					(pts
						(arc
							(start -0.1778 0.2794)
							(mid -0.249642 0.249642)
							(end -0.2794 0.1778)
						)
						(arc
							(start -0.2794 -0.1778)
							(mid -0.249642 -0.249642)
							(end -0.1778 -0.2794)
						)
						(arc
							(start 0.1778 -0.2794)
							(mid 0.249642 -0.249642)
							(end 0.2794 -0.1778)
						)
						(arc
							(start 0.2794 0.1778)
							(mid 0.249642 0.249642)
							(end 0.1778 0.2794)
						)
					)
					(width 0)
					(fill yes)
				)
			)
		)
		(pad "2" smd custom
			(at 0 0.4445)
			(size 0.1397 0.1397)
			(layers "B.Cu" "B.Mask" "B.Paste")
			(net "TWI_SCL2")
			(options
				(clearance outline)
				(anchor circle)
			)
			(primitives
				(gr_poly
					(pts
						(arc
							(start -0.1778 0.2794)
							(mid -0.249642 0.249642)
							(end -0.2794 0.1778)
						)
						(arc
							(start -0.2794 -0.1778)
							(mid -0.249642 -0.249642)
							(end -0.1778 -0.2794)
						)
						(arc
							(start 0.1778 -0.2794)
							(mid 0.249642 -0.249642)
							(end 0.2794 -0.1778)
						)
						(arc
							(start 0.2794 0.1778)
							(mid 0.249642 0.249642)
							(end 0.1778 0.2794)
						)
					)
					(width 0)
					(fill yes)
				)
			)
		)
	)
	(footprint ""
		(layer "B.Cu")
		(at 18.5166 -185.7502)
		(property "Reference" "C372"
			(at 0 0 0)
			(layer "B.SilkS")
			(hide yes)
			(effects
				(font
					(size 1.27 1.27)
				)
				(justify mirror)
			)
		)
		(property "Value" "SCD015U25V2KX-GP"
			(at -1.1811 -2.7051 0)
			(unlocked yes)
			(layer "B.Fab")
			(hide yes)
			(effects
				(font
					(size 1.016 1.016)
					(thickness 0.1524)
				)
				(justify mirror)
			)
		)
		(property "Device Type" "C402H22"
			(at -1.1811 -4.2291 0)
			(unlocked yes)
			(layer "B.Fab")
			(hide yes)
			(effects
				(font
					(size 1.016 1.016)
					(thickness 0.1524)
				)
				(justify mirror)
			)
		)
		(duplicate_pad_numbers_are_jumpers no)
		(fp_rect
			(start 0.4318 0.9525)
			(end -0.4318 -0.9525)
			(stroke
				(width 0)
				(type default)
			)
			(fill no)
			(layer "B.CrtYd")
		)
		(fp_rect
			(start 0.4318 0.9525)
			(end -0.4318 -0.9525)
			(stroke
				(width 0)
				(type default)
			)
			(fill no)
			(layer "B.Fab")
		)
		(pad "1" smd custom
			(at 0 -0.4445 180)
			(size 0.1524 0.1524)
			(layers "B.Cu" "B.Mask" "B.Paste")
			(net "MB0_CM_SENSE_P")
			(options
				(clearance outline)
				(anchor circle)
			)
			(primitives
				(gr_poly
					(pts
						(arc
							(start 0.3048 0.2032)
							(mid 0.275042 0.275042)
							(end 0.2032 0.3048)
						)
						(arc
							(start -0.2032 0.3048)
							(mid -0.275042 0.275042)
							(end -0.3048 0.2032)
						)
						(arc
							(start -0.3048 -0.2032)
							(mid -0.275042 -0.275042)
							(end -0.2032 -0.3048)
						)
						(arc
							(start 0.2032 -0.3048)
							(mid 0.275042 -0.275042)
							(end 0.3048 -0.2032)
						)
					)
					(width 0)
					(fill yes)
				)
			)
		)
		(pad "2" smd custom
			(at 0 0.4445 180)
			(size 0.1524 0.1524)
			(layers "B.Cu" "B.Mask" "B.Paste")
			(net "MB0_CM_SENSE_N")
			(options
				(clearance outline)
				(anchor circle)
			)
			(primitives
				(gr_poly
					(pts
						(arc
							(start 0.3048 0.2032)
							(mid 0.275042 0.275042)
							(end 0.2032 0.3048)
						)
						(arc
							(start -0.2032 0.3048)
							(mid -0.275042 0.275042)
							(end -0.3048 0.2032)
						)
						(arc
							(start -0.3048 -0.2032)
							(mid -0.275042 -0.275042)
							(end -0.2032 -0.3048)
						)
						(arc
							(start 0.2032 -0.3048)
							(mid 0.275042 -0.275042)
							(end 0.3048 -0.2032)
						)
					)
					(width 0)
					(fill yes)
				)
			)
		)
	)
	(footprint ""
		(layer "B.Cu")
		(at 53.975508 -120.807226 -90)
		(property "Reference" "R247"
			(at 0 0 90)
			(layer "B.SilkS")
			(hide yes)
			(effects
				(font
					(size 1.27 1.27)
				)
				(justify mirror)
			)
		)
		(property "Value" "0R2J-2-GP"
			(at -0.064008 -3.993896 270)
			(unlocked yes)
			(layer "B.Fab")
			(hide yes)
			(effects
				(font
					(size 1.016 1.016)
					(thickness 0.1524)
				)
				(justify mirror)
			)
		)
		(property "Device Type" "R402H16"
			(at -0.064008 -5.517896 270)
			(unlocked yes)
			(layer "B.Fab")
			(hide yes)
			(effects
				(font
					(size 1.016 1.016)
					(thickness 0.1524)
				)
				(justify mirror)
			)
		)
		(duplicate_pad_numbers_are_jumpers no)
		(fp_line
			(start -0.508 -0.9398)
			(end 0.508 -0.9398)
			(stroke
				(width 0.1524)
				(type default)
			)
			(layer "B.SilkS")
		)
		(fp_line
			(start 0.508 -0.9398)
			(end 0.508 0.9398)
			(stroke
				(width 0.1524)
				(type default)
			)
			(layer "B.SilkS")
		)
		(fp_rect
			(start 0.508 0.9398)
			(end -0.508 -0.9398)
			(stroke
				(width 0)
				(type default)
			)
			(fill no)
			(layer "B.CrtYd")
		)
		(fp_rect
			(start 0.508 0.9398)
			(end -0.508 -0.9398)
			(stroke
				(width 0)
				(type default)
			)
			(fill no)
			(layer "B.Fab")
		)
		(pad "1" smd custom
			(at 0 -0.4445 90)
			(size 0.1397 0.1397)
			(layers "B.Cu" "B.Mask" "B.Paste")
			(net "BMC_I2C5_D_PEB_DEVICE_SDA")
			(options
				(clearance outline)
				(anchor circle)
			)
			(primitives
				(gr_poly
					(pts
						(arc
							(start -0.1778 0.2794)
							(mid -0.249642 0.249642)
							(end -0.2794 0.1778)
						)
						(arc
							(start -0.2794 -0.1778)
							(mid -0.249642 -0.249642)
							(end -0.1778 -0.2794)
						)
						(arc
							(start 0.1778 -0.2794)
							(mid 0.249642 -0.249642)
							(end 0.2794 -0.1778)
						)
						(arc
							(start 0.2794 0.1778)
							(mid 0.249642 0.249642)
							(end 0.1778 0.2794)
						)
					)
					(width 0)
					(fill yes)
				)
			)
		)
		(pad "2" smd custom
			(at 0 0.4445 90)
			(size 0.1397 0.1397)
			(layers "B.Cu" "B.Mask" "B.Paste")
			(net "BMC0_SMB5_DAT")
			(options
				(clearance outline)
				(anchor circle)
			)
			(primitives
				(gr_poly
					(pts
						(arc
							(start -0.1778 0.2794)
							(mid -0.249642 0.249642)
							(end -0.2794 0.1778)
						)
						(arc
							(start -0.2794 -0.1778)
							(mid -0.249642 -0.249642)
							(end -0.1778 -0.2794)
						)
						(arc
							(start 0.1778 -0.2794)
							(mid 0.249642 -0.249642)
							(end 0.2794 -0.1778)
						)
						(arc
							(start 0.2794 0.1778)
							(mid 0.249642 0.249642)
							(end 0.1778 0.2794)
						)
					)
					(width 0)
					(fill yes)
				)
			)
		)
	)
	(footprint ""
		(layer "B.Cu")
		(at 335.820512 -172.432218)
		(property "Reference" "R4155"
			(at 0 0 0)
			(layer "B.SilkS")
			(hide yes)
			(effects
				(font
					(size 1.27 1.27)
				)
				(justify mirror)
			)
		)
		(property "Value" "4K7R2F-GP"
			(at -0.064008 -3.993896 0)
			(unlocked yes)
			(layer "B.Fab")
			(hide yes)
			(effects
				(font
					(size 1.016 1.016)
					(thickness 0.1524)
				)
				(justify mirror)
			)
		)
		(property "Device Type" "R402H16"
			(at -0.064008 -5.517896 0)
			(unlocked yes)
			(layer "B.Fab")
			(hide yes)
			(effects
				(font
					(size 1.016 1.016)
					(thickness 0.1524)
				)
				(justify mirror)
			)
		)
		(duplicate_pad_numbers_are_jumpers no)
		(fp_line
			(start -0.508 -0.9398)
			(end 0.508 -0.9398)
			(stroke
				(width 0.1524)
				(type default)
			)
			(layer "B.SilkS")
		)
		(fp_line
			(start 0.508 -0.9398)
			(end 0.508 0.9398)
			(stroke
				(width 0.1524)
				(type default)
			)
			(layer "B.SilkS")
		)
		(fp_rect
			(start 0.508 0.9398)
			(end -0.508 -0.9398)
			(stroke
				(width 0)
				(type default)
			)
			(fill no)
			(layer "B.CrtYd")
		)
		(fp_rect
			(start 0.508 0.9398)
			(end -0.508 -0.9398)
			(stroke
				(width 0)
				(type default)
			)
			(fill no)
			(layer "B.Fab")
		)
		(pad "1" smd custom
			(at 0 -0.4445 180)
			(size 0.1397 0.1397)
			(layers "B.Cu" "B.Mask" "B.Paste")
			(net "SSD_PERST#4")
			(options
				(clearance outline)
				(anchor circle)
			)
			(primitives
				(gr_poly
					(pts
						(arc
							(start -0.1778 0.2794)
							(mid -0.249642 0.249642)
							(end -0.2794 0.1778)
						)
						(arc
							(start -0.2794 -0.1778)
							(mid -0.249642 -0.249642)
							(end -0.1778 -0.2794)
						)
						(arc
							(start 0.1778 -0.2794)
							(mid 0.249642 -0.249642)
							(end 0.2794 -0.1778)
						)
						(arc
							(start 0.2794 0.1778)
							(mid 0.249642 0.249642)
							(end 0.1778 0.2794)
						)
					)
					(width 0)
					(fill yes)
				)
			)
		)
		(pad "2" smd custom
			(at 0 0.4445 180)
			(size 0.1397 0.1397)
			(layers "B.Cu" "B.Mask" "B.Paste")
			(net "P3V3_STBY")
			(options
				(clearance outline)
				(anchor circle)
			)
			(primitives
				(gr_poly
					(pts
						(arc
							(start -0.1778 0.2794)
							(mid -0.249642 0.249642)
							(end -0.2794 0.1778)
						)
						(arc
							(start -0.2794 -0.1778)
							(mid -0.249642 -0.249642)
							(end -0.1778 -0.2794)
						)
						(arc
							(start 0.1778 -0.2794)
							(mid 0.249642 -0.249642)
							(end 0.2794 -0.1778)
						)
						(arc
							(start 0.2794 0.1778)
							(mid 0.249642 0.249642)
							(end 0.1778 0.2794)
						)
					)
					(width 0)
					(fill yes)
				)
			)
		)
	)
	(footprint ""
		(layer "B.Cu")
		(at 133.268212 -199.753474)
		(property "Reference" "R3209"
			(at 0 0 0)
			(layer "B.SilkS")
			(hide yes)
			(effects
				(font
					(size 1.27 1.27)
				)
				(justify mirror)
			)
		)
		(property "Value" "0R2J-2-GP"
			(at -0.064008 -3.993896 0)
			(unlocked yes)
			(layer "B.Fab")
			(hide yes)
			(effects
				(font
					(size 1.016 1.016)
					(thickness 0.1524)
				)
				(justify mirror)
			)
		)
		(property "Device Type" "R402H16"
			(at -0.064008 -5.517896 0)
			(unlocked yes)
			(layer "B.Fab")
			(hide yes)
			(effects
				(font
					(size 1.016 1.016)
					(thickness 0.1524)
				)
				(justify mirror)
			)
		)
		(duplicate_pad_numbers_are_jumpers no)
		(fp_line
			(start -0.508 -0.9398)
			(end 0.508 -0.9398)
			(stroke
				(width 0.1524)
				(type default)
			)
			(layer "B.SilkS")
		)
		(fp_line
			(start 0.508 -0.9398)
			(end 0.508 0.9398)
			(stroke
				(width 0.1524)
				(type default)
			)
			(layer "B.SilkS")
		)
		(fp_rect
			(start 0.508 0.9398)
			(end -0.508 -0.9398)
			(stroke
				(width 0)
				(type default)
			)
			(fill no)
			(layer "B.CrtYd")
		)
		(fp_rect
			(start 0.508 0.9398)
			(end -0.508 -0.9398)
			(stroke
				(width 0)
				(type default)
			)
			(fill no)
			(layer "B.Fab")
		)
		(pad "1" smd custom
			(at 0 -0.4445 180)
			(size 0.1397 0.1397)
			(layers "B.Cu" "B.Mask" "B.Paste")
			(net "SSD_PERST_Y2")
			(options
				(clearance outline)
				(anchor circle)
			)
			(primitives
				(gr_poly
					(pts
						(arc
							(start -0.1778 0.2794)
							(mid -0.249642 0.249642)
							(end -0.2794 0.1778)
						)
						(arc
							(start -0.2794 -0.1778)
							(mid -0.249642 -0.249642)
							(end -0.1778 -0.2794)
						)
						(arc
							(start 0.1778 -0.2794)
							(mid 0.249642 -0.249642)
							(end 0.2794 -0.1778)
						)
						(arc
							(start 0.2794 0.1778)
							(mid 0.249642 0.249642)
							(end 0.1778 0.2794)
						)
					)
					(width 0)
					(fill yes)
				)
			)
		)
		(pad "2" smd custom
			(at 0 0.4445 180)
			(size 0.1397 0.1397)
			(layers "B.Cu" "B.Mask" "B.Paste")
			(net "SSD_PERST#2_R")
			(options
				(clearance outline)
				(anchor circle)
			)
			(primitives
				(gr_poly
					(pts
						(arc
							(start -0.1778 0.2794)
							(mid -0.249642 0.249642)
							(end -0.2794 0.1778)
						)
						(arc
							(start -0.2794 -0.1778)
							(mid -0.249642 -0.249642)
							(end -0.1778 -0.2794)
						)
						(arc
							(start 0.1778 -0.2794)
							(mid 0.249642 -0.249642)
							(end 0.2794 -0.1778)
						)
						(arc
							(start 0.2794 0.1778)
							(mid 0.249642 0.249642)
							(end 0.1778 0.2794)
						)
					)
					(width 0)
					(fill yes)
				)
			)
		)
	)
	(footprint ""
		(layer "B.Cu")
		(at 24.13 -123.0884 -90)
		(property "Reference" "R704"
			(at 0 0 90)
			(layer "B.SilkS")
			(hide yes)
			(effects
				(font
					(size 1.27 1.27)
				)
				(justify mirror)
			)
		)
		(property "Value" "0R2J-2-GP"
			(at -0.064008 -3.993896 270)
			(unlocked yes)
			(layer "B.Fab")
			(hide yes)
			(effects
				(font
					(size 1.016 1.016)
					(thickness 0.1524)
				)
				(justify mirror)
			)
		)
		(property "Device Type" "R402H16"
			(at -0.064008 -5.517896 270)
			(unlocked yes)
			(layer "B.Fab")
			(hide yes)
			(effects
				(font
					(size 1.016 1.016)
					(thickness 0.1524)
				)
				(justify mirror)
			)
		)
		(duplicate_pad_numbers_are_jumpers no)
		(fp_line
			(start -0.508 -0.9398)
			(end 0.508 -0.9398)
			(stroke
				(width 0.1524)
				(type default)
			)
			(layer "B.SilkS")
		)
		(fp_line
			(start 0.508 -0.9398)
			(end 0.508 0.9398)
			(stroke
				(width 0.1524)
				(type default)
			)
			(layer "B.SilkS")
		)
		(fp_rect
			(start 0.508 0.9398)
			(end -0.508 -0.9398)
			(stroke
				(width 0)
				(type default)
			)
			(fill no)
			(layer "B.CrtYd")
		)
		(fp_rect
			(start 0.508 0.9398)
			(end -0.508 -0.9398)
			(stroke
				(width 0)
				(type default)
			)
			(fill no)
			(layer "B.Fab")
		)
		(pad "1" smd custom
			(at 0 -0.4445 90)
			(size 0.1397 0.1397)
			(layers "B.Cu" "B.Mask" "B.Paste")
			(net "SPICK_R")
			(options
				(clearance outline)
				(anchor circle)
			)
			(primitives
				(gr_poly
					(pts
						(arc
							(start -0.1778 0.2794)
							(mid -0.249642 0.249642)
							(end -0.2794 0.1778)
						)
						(arc
							(start -0.2794 -0.1778)
							(mid -0.249642 -0.249642)
							(end -0.1778 -0.2794)
						)
						(arc
							(start 0.1778 -0.2794)
							(mid 0.249642 -0.249642)
							(end 0.2794 -0.1778)
						)
						(arc
							(start 0.2794 0.1778)
							(mid 0.249642 0.249642)
							(end 0.1778 0.2794)
						)
					)
					(width 0)
					(fill yes)
				)
			)
		)
		(pad "2" smd custom
			(at 0 0.4445 90)
			(size 0.1397 0.1397)
			(layers "B.Cu" "B.Mask" "B.Paste")
			(net "SPICK")
			(options
				(clearance outline)
				(anchor circle)
			)
			(primitives
				(gr_poly
					(pts
						(arc
							(start -0.1778 0.2794)
							(mid -0.249642 0.249642)
							(end -0.2794 0.1778)
						)
						(arc
							(start -0.2794 -0.1778)
							(mid -0.249642 -0.249642)
							(end -0.1778 -0.2794)
						)
						(arc
							(start 0.1778 -0.2794)
							(mid 0.249642 -0.249642)
							(end 0.2794 -0.1778)
						)
						(arc
							(start 0.2794 0.1778)
							(mid 0.249642 0.249642)
							(end 0.1778 0.2794)
						)
					)
					(width 0)
					(fill yes)
				)
			)
		)
	)
)
